FILE_TYPE = MACRO_DRAWING;
SET COLOR_WIRE YELLOW;
SET COLOR_PROP ORANGE;
SET COLOR_DOT WHITE;
SET COLOR_ARC YELLOW;
SET COLOR_BODY GREEN;
SET COLOR_NOTE PURPLE;
SET PROP_DISPLAY VALUE;
SET PAGE_NUMBER P159;
FORCEADD QUANTA_TITLE_BLOCK_C..1
(25 275);
FORCEPROP 1 LAST CUSTOM_TXT_CDS <NAME_2>
J 0
(-3150 325);
FORCEPROP 1 LAST CUSTOM_TXT_CDS <NAME_1>
J 0
(-3150 450);
FORCEPROP 1 LAST Q_TITLE P12V_MEM MOS SWITCH
J 0
(-9341 301);
DISPLAY 2.446809 (-9341 301);
PAINT GREEN (-9341 301);
FORCEPROP 1 LAST Q_DEPT BU9
J 1
(-3738 324);
DISPLAY 1.957447 (-3738 324);
PAINT GREEN (-3738 324);
FORCEPROP 2 LAST CUSTOM_TXT_CDS <CON_PAGE_NUM> OF <CON_TOTAL_PAGES>
J 0
(-421 293);
DISPLAY 0.978723 (-421 293);
FORCEPROP 2 LAST CUSTOM_TXT_CDS <Q_REV>
J 0
(-159 378);
DISPLAY 1.212766 (-159 378);
FORCEPROP 2 LAST CUSTOM_TXT_CDS <Q_NUMBER>
J 0
(-1378 378);
DISPLAY 1.212766 (-1378 378);
FORCEPROP 2 LAST CUSTOM_TXT_CDS <Q_PROJ>
J 0
(-2357 377);
DISPLAY 1.212766 (-2357 377);
FORCEPROP 2 LAST CUSTOM_TXT_CDS <CON_LAST_MODIFIED>
J 0
(-1860 290);
DISPLAY 0.978723 (-1860 290);
FORCEPROP 1 LAST COMMENT_BODY TRUE
J 0
(37 262);
DISPLAY 0.978723 (37 262);
PAINT GREEN (37 262);
DISPLAY INVISIBLE (37 262);
FORCEPROP 2 LAST PAGE_BORDER TRUE
J 0
(-7865 5525);
DISPLAY 0.638298 (-7865 5525);
PAINT PINK (-7865 5525);
DISPLAY INVISIBLE (-7865 5525);
FORCEPROP 2 LAST CDS_LIB pure_quanta
J 0
(25 275);
PAINT MONO (25 275);
DISPLAY INVISIBLE (25 275);
FORCEPROP 1 LAST CDS_LMAN_SYM_OUTLINE -9475,6775,100,-125
J 0
(25 275);
DISPLAY 0.468085 (25 275);
PAINT GREEN (25 275);
DISPLAY INVISIBLE (25 275);
FORCEPROP 2 LAST CDS_XR_PAGE_TITLE CR-159 : @T6G_MB_LIB.T6G(SCH_1):PAGE159
J 0
(-7865 5525);
DISPLAY 0.638298 (-7865 5525);
PAINT PINK (-7865 5525);
DISPLAY INVISIBLE (-7865 5525);
FORCEPROP 2 LAST CUSTOM_TXT_CDS <XR_PAGE_TITLE>
J 0
(-7865 5525);
DISPLAY 0.638298 (-7865 5525);
PAINT PINK (-7865 5525);
DISPLAY INVISIBLE (-7865 5525);
FORCEPROP 0 LAST CDS_CON_LAST_MODIFIED Wed Mar 09 20:41:19 2022
J 0
(-1860 290);
PAINT MONO (-1860 290);
DISPLAY INVISIBLE (-1860 290);
QUIT
